# S9S_MB_2U (Grand Teton) — schematic netlist excerpt (pin names and nets, part order shuffled) for the footprints in the layout excerpt that follows; sources: Cadence DE-HDL packaged netlist, KiCad conversion of 03242023_DA0F0TMBIJ0_F0T_Motherboard_J_brd_V01_OCP.brd

C2859  Q_CAP  1000PF 50V 5% EMPTY  pkg 0402  page 284 : A = PWRGD_PVCCIN_CPU1_R ; B = GND
PR2381  Q_RES  26.1K 0.1% EMPTY  pkg 0402LF  page 299 : A = PVPP_HBM_CPU1_FB ; B = FM_HBM_VPP_SEL_CPU1_D

(kicad_pcb
	(version 20260206)
	(generator "pcbnew")
	(generator_version "10.0")
	(general
		(thickness 1.6)
		(legacy_teardrops no)
	)
	(paper "A4")
	(title_block
		(title "03242023_DA0F0TMBIJ0_F0T_Motherboard_J_brd_V01_OCP.brd")
		(comment 1 "Grand Teton / footprints 2662-2663 of 6105")
	)
	(layers
		(0 "F.Cu" signal "TOP")
		(4 "In1.Cu" signal "GND")
		(6 "In2.Cu" signal "IN1")
		(8 "In3.Cu" signal "GND1")
		(10 "In4.Cu" signal "IN2")
		(12 "In5.Cu" signal "GND2")
		(14 "In6.Cu" signal "IN3")
		(16 "In7.Cu" signal "GND3")
		(18 "In8.Cu" signal "VCC")
		(20 "In9.Cu" signal "VCC1")
		(22 "In10.Cu" signal "GND4")
		(24 "In11.Cu" signal "IN4")
		(26 "In12.Cu" signal "GND5")
		(28 "In13.Cu" signal "IN5")
		(30 "In14.Cu" signal "GND6")
		(32 "In15.Cu" signal "IN6")
		(34 "In16.Cu" signal "GND7")
		(2 "B.Cu" signal "BOTTOM")
		(9 "F.Adhes" user "F.Adhesive")
		(11 "B.Adhes" user "B.Adhesive")
		(13 "F.Paste" user "Package Geometry/Pastemask Top")
		(15 "B.Paste" user "Package Geometry/Pastemask Bottom")
		(5 "F.SilkS" user "Ref Des/Silkscreen Top")
		(7 "B.SilkS" user "Ref Des/Silkscreen Bottom")
		(1 "F.Mask" user "Board Geometry/Soldermask Top")
		(3 "B.Mask" user "Board Geometry/Soldermask Bottom")
		(17 "Dwgs.User" user "User.Drawings")
		(19 "Cmts.User" user "User.Comments")
		(21 "Eco1.User" user "User.Eco1")
		(23 "Eco2.User" user "User.Eco2")
		(25 "Edge.Cuts" user "Board Geometry/Outline")
		(27 "Margin" user)
		(31 "F.CrtYd" user "Package Geometry/Place Bound Top")
		(29 "B.CrtYd" user "Package Geometry/Place Bound Bottom")
		(35 "F.Fab" user "Ref Des/Assembly Top")
		(33 "B.Fab" user "Ref Des/Assembly Bottom")
	)
	(footprint ""
		(layer "F.Cu")
		(at 103.40975 -360.934762 90)
		(property "Reference" "C2859"
			(at 0 0 90)
			(layer "F.SilkS")
			(hide yes)
			(effects
				(font
					(size 1.27 1.27)
				)
			)
		)
		(property "Value" ""
			(at 0 0 90)
			(layer "F.Fab")
			(effects
				(font
					(size 1.27 1.27)
				)
			)
		)
		(duplicate_pad_numbers_are_jumpers no)
		(fp_line
			(start 0.7874 -0.4064)
			(end 0.7874 0.4064)
			(stroke
				(width 0.1524)
				(type default)
			)
			(layer "F.SilkS")
		)
		(fp_line
			(start -0.7874 -0.4064)
			(end 0.7874 -0.4064)
			(stroke
				(width 0.1524)
				(type default)
			)
			(layer "F.SilkS")
		)
		(fp_line
			(start 0.7874 0.4064)
			(end -0.7874 0.4064)
			(stroke
				(width 0.1524)
				(type default)
			)
			(layer "F.SilkS")
		)
		(fp_line
			(start -0.7874 0.4064)
			(end -0.7874 -0.4064)
			(stroke
				(width 0.1524)
				(type default)
			)
			(layer "F.SilkS")
		)
		(fp_line
			(start -0.12065 -0.305054)
			(end -0.12065 -0.2794)
			(stroke
				(width 0.1)
				(type default)
			)
			(layer "F.Fab")
		)
		(fp_line
			(start -0.67945 -0.305054)
			(end -0.12065 -0.305054)
			(stroke
				(width 0.1)
				(type default)
			)
			(layer "F.Fab")
		)
		(fp_line
			(start 0.67945 -0.3048)
			(end 0.67945 0.3048)
			(stroke
				(width 0.1)
				(type default)
			)
			(layer "F.Fab")
		)
		(fp_line
			(start 0.12065 -0.3048)
			(end 0.67945 -0.3048)
			(stroke
				(width 0.1)
				(type default)
			)
			(layer "F.Fab")
		)
		(fp_line
			(start 0.12065 -0.2794)
			(end 0.12065 -0.3048)
			(stroke
				(width 0.1)
				(type default)
			)
			(layer "F.Fab")
		)
		(fp_line
			(start -0.12065 -0.2794)
			(end 0.12065 -0.2794)
			(stroke
				(width 0.1)
				(type default)
			)
			(layer "F.Fab")
		)
		(fp_line
			(start 0.120396 0.2794)
			(end -0.12065 0.2794)
			(stroke
				(width 0.1)
				(type default)
			)
			(layer "F.Fab")
		)
		(fp_line
			(start -0.12065 0.2794)
			(end -0.12065 0.3048)
			(stroke
				(width 0.1)
				(type default)
			)
			(layer "F.Fab")
		)
		(fp_line
			(start 0.67945 0.3048)
			(end 0.120396 0.3048)
			(stroke
				(width 0.1)
				(type default)
			)
			(layer "F.Fab")
		)
		(fp_line
			(start 0.120396 0.3048)
			(end 0.120396 0.2794)
			(stroke
				(width 0.1)
				(type default)
			)
			(layer "F.Fab")
		)
		(fp_line
			(start -0.12065 0.3048)
			(end -0.67945 0.3048)
			(stroke
				(width 0.1)
				(type default)
			)
			(layer "F.Fab")
		)
		(fp_line
			(start -0.67945 0.3048)
			(end -0.67945 -0.305054)
			(stroke
				(width 0.1)
				(type default)
			)
			(layer "F.Fab")
		)
		(pad "1" smd circle
			(at -0.40005 0 90)
			(size 0 0)
			(layers "F.Cu" "F.Mask" "F.Paste")
			(net "PWRGD_PVCCIN_CPU1_R")
		)
		(pad "2" smd circle
			(at 0.40005 0 90)
			(size 0 0)
			(layers "F.Cu" "F.Mask" "F.Paste")
			(net "GND")
		)
	)
	(footprint ""
		(layer "F.Cu")
		(at 119.02948 -357.114348 90)
		(property "Reference" "PR2381"
			(at 0 0 90)
			(layer "F.SilkS")
			(hide yes)
			(effects
				(font
					(size 1.27 1.27)
				)
			)
		)
		(property "Value" ""
			(at 0 0 90)
			(layer "F.Fab")
			(effects
				(font
					(size 1.27 1.27)
				)
			)
		)
		(duplicate_pad_numbers_are_jumpers no)
		(fp_line
			(start 0.7874 -0.4064)
			(end 0.7874 0.4064)
			(stroke
				(width 0.1524)
				(type default)
			)
			(layer "F.SilkS")
		)
		(fp_line
			(start -0.7874 -0.4064)
			(end 0.7874 -0.4064)
			(stroke
				(width 0.1524)
				(type default)
			)
			(layer "F.SilkS")
		)
		(fp_line
			(start 0.7874 0.4064)
			(end -0.7874 0.4064)
			(stroke
				(width 0.1524)
				(type default)
			)
			(layer "F.SilkS")
		)
		(fp_line
			(start -0.7874 0.4064)
			(end -0.7874 -0.4064)
			(stroke
				(width 0.1524)
				(type default)
			)
			(layer "F.SilkS")
		)
		(fp_line
			(start -0.12065 -0.305054)
			(end -0.12065 -0.2794)
			(stroke
				(width 0.1)
				(type default)
			)
			(layer "F.Fab")
		)
		(fp_line
			(start -0.67945 -0.305054)
			(end -0.12065 -0.305054)
			(stroke
				(width 0.1)
				(type default)
			)
			(layer "F.Fab")
		)
		(fp_line
			(start 0.67945 -0.3048)
			(end 0.67945 0.3048)
			(stroke
				(width 0.1)
				(type default)
			)
			(layer "F.Fab")
		)
		(fp_line
			(start 0.12065 -0.3048)
			(end 0.67945 -0.3048)
			(stroke
				(width 0.1)
				(type default)
			)
			(layer "F.Fab")
		)
		(fp_line
			(start 0.12065 -0.2794)
			(end 0.12065 -0.3048)
			(stroke
				(width 0.1)
				(type default)
			)
			(layer "F.Fab")
		)
		(fp_line
			(start -0.12065 -0.2794)
			(end 0.12065 -0.2794)
			(stroke
				(width 0.1)
				(type default)
			)
			(layer "F.Fab")
		)
		(fp_line
			(start 0.120396 0.2794)
			(end -0.12065 0.2794)
			(stroke
				(width 0.1)
				(type default)
			)
			(layer "F.Fab")
		)
		(fp_line
			(start -0.12065 0.2794)
			(end -0.12065 0.3048)
			(stroke
				(width 0.1)
				(type default)
			)
			(layer "F.Fab")
		)
		(fp_line
			(start 0.67945 0.3048)
			(end 0.120396 0.3048)
			(stroke
				(width 0.1)
				(type default)
			)
			(layer "F.Fab")
		)
		(fp_line
			(start 0.120396 0.3048)
			(end 0.120396 0.2794)
			(stroke
				(width 0.1)
				(type default)
			)
			(layer "F.Fab")
		)
		(fp_line
			(start -0.12065 0.3048)
			(end -0.67945 0.3048)
			(stroke
				(width 0.1)
				(type default)
			)
			(layer "F.Fab")
		)
		(fp_line
			(start -0.67945 0.3048)
			(end -0.67945 -0.305054)
			(stroke
				(width 0.1)
				(type default)
			)
			(layer "F.Fab")
		)
		(pad "1" smd circle
			(at -0.40005 0 90)
			(size 0 0)
			(layers "F.Cu" "F.Mask" "F.Paste")
			(net "PVPP_HBM_CPU1_FB")
		)
		(pad "2" smd circle
			(at 0.40005 0 90)
			(size 0 0)
			(layers "F.Cu" "F.Mask" "F.Paste")
			(net "FM_HBM_VPP_SEL_CPU1_D")
		)
	)
)
